FILE_TYPE = MULTI_PHYS_TABLE;

PART 'CONN_USB_1X5_G2_GH4_F_RA_SMT'
CLASS=IO

{========================================================================================}
:CLS_PN          | VALUE    = JEDEC_TYPE                    | ALT_SYMBOLS                     | DESCRIPTION                                       ;
{========================================================================================}
 'G200-12192-01' | '1050171001'(!)    = 'S_F_USB_1X5_G2_GH4_RA_P0256' | '(S_F_USB_1X5_G2_GH4_RA_P0256)' | 'CON,MICRO USB BOTTOM MOUNT RECEPTACLE,B TYPE,RA,SMT'

END_PART

END.

